# S9S_MB_2U (Grand Teton) — schematic netlist excerpt (pin names and nets, part order shuffled) for the footprints in the layout excerpt that follows; sources: Cadence DE-HDL packaged netlist, KiCad conversion of 03242023_DA0F0TMBIJ0_F0T_Motherboard_J_brd_V01_OCP.brd

R1024  Q_RES  100 1% CHIP  pkg 0402LF  page 182 : A = JTAG_DBP_TCK_PCH ; B = GND
R4725  Q_RES  4.7K 5% CHIP  pkg 0402LF  page 144 : A = P3V3_AUX ; B = PRSNT_SWB
H24  HOLE  EMPTY  pkg TH  page 311 : \1\ = NC

(kicad_pcb
	(version 20260206)
	(generator "pcbnew")
	(generator_version "10.0")
	(general
		(thickness 1.6)
		(legacy_teardrops no)
	)
	(paper "A4")
	(title_block
		(title "03242023_DA0F0TMBIJ0_F0T_Motherboard_J_brd_V01_OCP.brd")
		(comment 1 "Grand Teton / footprints 3631-3633 of 6105")
	)
	(layers
		(0 "F.Cu" signal "TOP")
		(4 "In1.Cu" signal "GND")
		(6 "In2.Cu" signal "IN1")
		(8 "In3.Cu" signal "GND1")
		(10 "In4.Cu" signal "IN2")
		(12 "In5.Cu" signal "GND2")
		(14 "In6.Cu" signal "IN3")
		(16 "In7.Cu" signal "GND3")
		(18 "In8.Cu" signal "VCC")
		(20 "In9.Cu" signal "VCC1")
		(22 "In10.Cu" signal "GND4")
		(24 "In11.Cu" signal "IN4")
		(26 "In12.Cu" signal "GND5")
		(28 "In13.Cu" signal "IN5")
		(30 "In14.Cu" signal "GND6")
		(32 "In15.Cu" signal "IN6")
		(34 "In16.Cu" signal "GND7")
		(2 "B.Cu" signal "BOTTOM")
		(9 "F.Adhes" user "F.Adhesive")
		(11 "B.Adhes" user "B.Adhesive")
		(13 "F.Paste" user "Package Geometry/Pastemask Top")
		(15 "B.Paste" user "Package Geometry/Pastemask Bottom")
		(5 "F.SilkS" user "Ref Des/Silkscreen Top")
		(7 "B.SilkS" user "Ref Des/Silkscreen Bottom")
		(1 "F.Mask" user "Board Geometry/Soldermask Top")
		(3 "B.Mask" user "Board Geometry/Soldermask Bottom")
		(17 "Dwgs.User" user "User.Drawings")
		(19 "Cmts.User" user "User.Comments")
		(21 "Eco1.User" user "User.Eco1")
		(23 "Eco2.User" user "User.Eco2")
		(25 "Edge.Cuts" user "Board Geometry/Outline")
		(27 "Margin" user)
		(31 "F.CrtYd" user "Package Geometry/Place Bound Top")
		(29 "B.CrtYd" user "Package Geometry/Place Bound Bottom")
		(35 "F.Fab" user "Ref Des/Assembly Top")
		(33 "B.Fab" user "Ref Des/Assembly Bottom")
	)
	(footprint ""
		(layer "F.Cu")
		(at 77.920088 -251.76988)
		(property "Reference" "H24"
			(at -4.47802 -1.615948 0)
			(unlocked yes)
			(layer "F.SilkS")
			(effects
				(font
					(size 0.7874 0.5842)
					(thickness 0.1524)
				)
				(justify left)
			)
		)
		(property "Value" ""
			(at 0 0 0)
			(layer "F.Fab")
			(effects
				(font
					(size 1.27 1.27)
				)
			)
		)
		(duplicate_pad_numbers_are_jumpers no)
		(fp_circle
			(center 0 0)
			(end 2.5273 0)
			(stroke
				(width 0.1524)
				(type default)
			)
			(fill no)
			(layer "F.SilkS")
		)
		(fp_circle
			(center 0 0)
			(end 2.5273 0)
			(stroke
				(width 0.1524)
				(type default)
			)
			(fill no)
			(layer "B.SilkS")
		)
		(fp_circle
			(center 0 0)
			(end 2.5273 0)
			(stroke
				(width 0.1)
				(type default)
			)
			(fill no)
			(layer "B.Fab")
		)
		(fp_circle
			(center 0 0)
			(end 2.5273 0)
			(stroke
				(width 0.1)
				(type default)
			)
			(fill no)
			(layer "F.Fab")
		)
		(pad "" np_thru_hole circle
			(at 0 0)
			(size 3.429 3.429)
			(drill 3.429)
			(layers "*.Cu" "*.Mask")
			(clearance 0.381)
			(thermal_gap 0.381)
		)
	)
	(footprint ""
		(layer "F.Cu")
		(at 106.7308 -410.6164 180)
		(property "Reference" "R4725"
			(at 0 0 180)
			(layer "F.SilkS")
			(hide yes)
			(effects
				(font
					(size 1.27 1.27)
				)
			)
		)
		(property "Value" ""
			(at 0 0 180)
			(layer "F.Fab")
			(effects
				(font
					(size 1.27 1.27)
				)
			)
		)
		(duplicate_pad_numbers_are_jumpers no)
		(fp_line
			(start 0.7874 0.4064)
			(end -0.7874 0.4064)
			(stroke
				(width 0.1524)
				(type default)
			)
			(layer "F.SilkS")
		)
		(fp_line
			(start 0.7874 -0.4064)
			(end 0.7874 0.4064)
			(stroke
				(width 0.1524)
				(type default)
			)
			(layer "F.SilkS")
		)
		(fp_line
			(start -0.7874 0.4064)
			(end -0.7874 -0.4064)
			(stroke
				(width 0.1524)
				(type default)
			)
			(layer "F.SilkS")
		)
		(fp_line
			(start -0.7874 -0.4064)
			(end 0.7874 -0.4064)
			(stroke
				(width 0.1524)
				(type default)
			)
			(layer "F.SilkS")
		)
		(fp_line
			(start 0.67945 0.3048)
			(end 0.120396 0.3048)
			(stroke
				(width 0.1)
				(type default)
			)
			(layer "F.Fab")
		)
		(fp_line
			(start 0.67945 -0.3048)
			(end 0.67945 0.3048)
			(stroke
				(width 0.1)
				(type default)
			)
			(layer "F.Fab")
		)
		(fp_line
			(start 0.12065 -0.2794)
			(end 0.12065 -0.3048)
			(stroke
				(width 0.1)
				(type default)
			)
			(layer "F.Fab")
		)
		(fp_line
			(start 0.12065 -0.3048)
			(end 0.67945 -0.3048)
			(stroke
				(width 0.1)
				(type default)
			)
			(layer "F.Fab")
		)
		(fp_line
			(start 0.120396 0.3048)
			(end 0.120396 0.2794)
			(stroke
				(width 0.1)
				(type default)
			)
			(layer "F.Fab")
		)
		(fp_line
			(start 0.120396 0.2794)
			(end -0.12065 0.2794)
			(stroke
				(width 0.1)
				(type default)
			)
			(layer "F.Fab")
		)
		(fp_line
			(start -0.12065 0.3048)
			(end -0.67945 0.3048)
			(stroke
				(width 0.1)
				(type default)
			)
			(layer "F.Fab")
		)
		(fp_line
			(start -0.12065 0.2794)
			(end -0.12065 0.3048)
			(stroke
				(width 0.1)
				(type default)
			)
			(layer "F.Fab")
		)
		(fp_line
			(start -0.12065 -0.2794)
			(end 0.12065 -0.2794)
			(stroke
				(width 0.1)
				(type default)
			)
			(layer "F.Fab")
		)
		(fp_line
			(start -0.12065 -0.305054)
			(end -0.12065 -0.2794)
			(stroke
				(width 0.1)
				(type default)
			)
			(layer "F.Fab")
		)
		(fp_line
			(start -0.67945 0.3048)
			(end -0.67945 -0.305054)
			(stroke
				(width 0.1)
				(type default)
			)
			(layer "F.Fab")
		)
		(fp_line
			(start -0.67945 -0.305054)
			(end -0.12065 -0.305054)
			(stroke
				(width 0.1)
				(type default)
			)
			(layer "F.Fab")
		)
		(pad "1" smd circle
			(at -0.40005 0 180)
			(size 0 0)
			(layers "F.Cu" "F.Mask" "F.Paste")
			(net "P3V3_AUX")
		)
		(pad "2" smd circle
			(at 0.40005 0 180)
			(size 0 0)
			(layers "F.Cu" "F.Mask" "F.Paste")
			(net "PRSNT_SWB")
		)
	)
	(footprint ""
		(layer "F.Cu")
		(at 346.995496 -26.804366 -90)
		(property "Reference" "R1024"
			(at 0 0 270)
			(layer "F.SilkS")
			(hide yes)
			(effects
				(font
					(size 1.27 1.27)
				)
			)
		)
		(property "Value" ""
			(at 0 0 270)
			(layer "F.Fab")
			(effects
				(font
					(size 1.27 1.27)
				)
			)
		)
		(duplicate_pad_numbers_are_jumpers no)
		(fp_line
			(start -0.7874 0.4064)
			(end -0.7874 -0.4064)
			(stroke
				(width 0.1524)
				(type default)
			)
			(layer "F.SilkS")
		)
		(fp_line
			(start 0.7874 0.4064)
			(end -0.7874 0.4064)
			(stroke
				(width 0.1524)
				(type default)
			)
			(layer "F.SilkS")
		)
		(fp_line
			(start -0.7874 -0.4064)
			(end 0.7874 -0.4064)
			(stroke
				(width 0.1524)
				(type default)
			)
			(layer "F.SilkS")
		)
		(fp_line
			(start 0.7874 -0.4064)
			(end 0.7874 0.4064)
			(stroke
				(width 0.1524)
				(type default)
			)
			(layer "F.SilkS")
		)
		(fp_line
			(start -0.67945 0.3048)
			(end -0.67945 -0.305054)
			(stroke
				(width 0.1)
				(type default)
			)
			(layer "F.Fab")
		)
		(fp_line
			(start -0.12065 0.3048)
			(end -0.67945 0.3048)
			(stroke
				(width 0.1)
				(type default)
			)
			(layer "F.Fab")
		)
		(fp_line
			(start 0.120396 0.3048)
			(end 0.120396 0.2794)
			(stroke
				(width 0.1)
				(type default)
			)
			(layer "F.Fab")
		)
		(fp_line
			(start 0.67945 0.3048)
			(end 0.120396 0.3048)
			(stroke
				(width 0.1)
				(type default)
			)
			(layer "F.Fab")
		)
		(fp_line
			(start -0.12065 0.2794)
			(end -0.12065 0.3048)
			(stroke
				(width 0.1)
				(type default)
			)
			(layer "F.Fab")
		)
		(fp_line
			(start 0.120396 0.2794)
			(end -0.12065 0.2794)
			(stroke
				(width 0.1)
				(type default)
			)
			(layer "F.Fab")
		)
		(fp_line
			(start -0.12065 -0.2794)
			(end 0.12065 -0.2794)
			(stroke
				(width 0.1)
				(type default)
			)
			(layer "F.Fab")
		)
		(fp_line
			(start 0.12065 -0.2794)
			(end 0.12065 -0.3048)
			(stroke
				(width 0.1)
				(type default)
			)
			(layer "F.Fab")
		)
		(fp_line
			(start 0.12065 -0.3048)
			(end 0.67945 -0.3048)
			(stroke
				(width 0.1)
				(type default)
			)
			(layer "F.Fab")
		)
		(fp_line
			(start 0.67945 -0.3048)
			(end 0.67945 0.3048)
			(stroke
				(width 0.1)
				(type default)
			)
			(layer "F.Fab")
		)
		(fp_line
			(start -0.67945 -0.305054)
			(end -0.12065 -0.305054)
			(stroke
				(width 0.1)
				(type default)
			)
			(layer "F.Fab")
		)
		(fp_line
			(start -0.12065 -0.305054)
			(end -0.12065 -0.2794)
			(stroke
				(width 0.1)
				(type default)
			)
			(layer "F.Fab")
		)
		(pad "1" smd circle
			(at -0.40005 0 270)
			(size 0 0)
			(layers "F.Cu" "F.Mask" "F.Paste")
			(net "JTAG_DBP_TCK_PCH")
		)
		(pad "2" smd circle
			(at 0.40005 0 270)
			(size 0 0)
			(layers "F.Cu" "F.Mask" "F.Paste")
			(net "GND")
		)
	)
)
